(kicad_pcb
	(version 20260206)
	(generator "pcbnew")
	(generator_version "10.0")
	(general
		(thickness 1.6)
		(legacy_teardrops no)
	)
	(paper "A4")
	(title_block
		(title "04192023_DAF0TMB3IC0_F0TG_MB_C_brd_V02_OCP.brd")
		(comment 1 "Grand Teton / footprints 975-981 of 8354")
	)
	(layers
		(0 "F.Cu" signal "TOP")
		(4 "In1.Cu" signal "GND")
		(6 "In2.Cu" signal "IN1")
		(8 "In3.Cu" signal "GND1")
		(10 "In4.Cu" signal "IN2")
		(12 "In5.Cu" signal "GND2")
		(14 "In6.Cu" signal "IN3")
		(16 "In7.Cu" signal "GND3")
		(18 "In8.Cu" signal "VCC")
		(20 "In9.Cu" signal "VCC1")
		(22 "In10.Cu" signal "GND4")
		(24 "In11.Cu" signal "IN4")
		(26 "In12.Cu" signal "GND5")
		(28 "In13.Cu" signal "IN5")
		(30 "In14.Cu" signal "GND6")
		(32 "In15.Cu" signal "IN6")
		(34 "In16.Cu" signal "GND7")
		(2 "B.Cu" signal "BOTTOM")
		(9 "F.Adhes" user "F.Adhesive")
		(11 "B.Adhes" user "B.Adhesive")
		(13 "F.Paste" user "Package Geometry/Pastemask Top")
		(15 "B.Paste" user "Package Geometry/Pastemask Bottom")
		(5 "F.SilkS" user "Ref Des/Silkscreen Top")
		(7 "B.SilkS" user "Ref Des/Silkscreen Bottom")
		(1 "F.Mask" user "Board Geometry/Soldermask Top")
		(3 "B.Mask" user "Board Geometry/Soldermask Bottom")
		(17 "Dwgs.User" user "User.Drawings")
		(19 "Cmts.User" user "User.Comments")
		(21 "Eco1.User" user "User.Eco1")
		(23 "Eco2.User" user "User.Eco2")
		(25 "Edge.Cuts" user "Board Geometry/Outline")
		(27 "Margin" user)
		(31 "F.CrtYd" user "Package Geometry/Place Bound Top")
		(29 "B.CrtYd" user "Package Geometry/Place Bound Bottom")
		(35 "F.Fab" user "Ref Des/Assembly Top")
		(33 "B.Fab" user "Ref Des/Assembly Bottom")
	)
	(footprint ""
		(layer "F.Cu")
		(at 188.296804 -426.353478 -90)
		(property "Reference" "R3516"
			(at 0 0 270)
			(layer "F.SilkS")
			(hide yes)
			(effects
				(font
					(size 1.27 1.27)
				)
			)
		)
		(property "Value" ""
			(at 0 0 270)
			(layer "F.Fab")
			(effects
				(font
					(size 1.27 1.27)
				)
			)
		)
		(duplicate_pad_numbers_are_jumpers no)
		(fp_line
			(start -0.7874 0.4064)
			(end -0.7874 -0.4064)
			(stroke
				(width 0.1524)
				(type default)
			)
			(layer "F.SilkS")
		)
		(fp_line
			(start 0.7874 0.4064)
			(end -0.7874 0.4064)
			(stroke
				(width 0.1524)
				(type default)
			)
			(layer "F.SilkS")
		)
		(fp_line
			(start -0.7874 -0.4064)
			(end 0.7874 -0.4064)
			(stroke
				(width 0.1524)
				(type default)
			)
			(layer "F.SilkS")
		)
		(fp_line
			(start 0.7874 -0.4064)
			(end 0.7874 0.4064)
			(stroke
				(width 0.1524)
				(type default)
			)
			(layer "F.SilkS")
		)
		(fp_line
			(start -0.67945 0.3048)
			(end -0.67945 -0.305054)
			(stroke
				(width 0.1)
				(type default)
			)
			(layer "F.Fab")
		)
		(fp_line
			(start -0.12065 0.3048)
			(end -0.67945 0.3048)
			(stroke
				(width 0.1)
				(type default)
			)
			(layer "F.Fab")
		)
		(fp_line
			(start 0.120396 0.3048)
			(end 0.120396 0.2794)
			(stroke
				(width 0.1)
				(type default)
			)
			(layer "F.Fab")
		)
		(fp_line
			(start 0.67945 0.3048)
			(end 0.120396 0.3048)
			(stroke
				(width 0.1)
				(type default)
			)
			(layer "F.Fab")
		)
		(fp_line
			(start -0.12065 0.2794)
			(end -0.12065 0.3048)
			(stroke
				(width 0.1)
				(type default)
			)
			(layer "F.Fab")
		)
		(fp_line
			(start 0.120396 0.2794)
			(end -0.12065 0.2794)
			(stroke
				(width 0.1)
				(type default)
			)
			(layer "F.Fab")
		)
		(fp_line
			(start -0.12065 -0.2794)
			(end 0.12065 -0.2794)
			(stroke
				(width 0.1)
				(type default)
			)
			(layer "F.Fab")
		)
		(fp_line
			(start 0.12065 -0.2794)
			(end 0.12065 -0.3048)
			(stroke
				(width 0.1)
				(type default)
			)
			(layer "F.Fab")
		)
		(fp_line
			(start 0.12065 -0.3048)
			(end 0.67945 -0.3048)
			(stroke
				(width 0.1)
				(type default)
			)
			(layer "F.Fab")
		)
		(fp_line
			(start 0.67945 -0.3048)
			(end 0.67945 0.3048)
			(stroke
				(width 0.1)
				(type default)
			)
			(layer "F.Fab")
		)
		(fp_line
			(start -0.67945 -0.305054)
			(end -0.12065 -0.305054)
			(stroke
				(width 0.1)
				(type default)
			)
			(layer "F.Fab")
		)
		(fp_line
			(start -0.12065 -0.305054)
			(end -0.12065 -0.2794)
			(stroke
				(width 0.1)
				(type default)
			)
			(layer "F.Fab")
		)
		(pad "1" smd circle
			(at -0.40005 0 270)
			(size 0 0)
			(layers "F.Cu" "F.Mask" "F.Paste")
			(net "GPU_BASE_ID0")
		)
		(pad "2" smd circle
			(at 0.40005 0 270)
			(size 0 0)
			(layers "F.Cu" "F.Mask" "F.Paste")
			(net "GPU_BASE_ID0_R")
		)
	)
	(footprint ""
		(layer "F.Cu")
		(at 105.84561 -66.58991 180)
		(property "Reference" "R6219"
			(at 0 0 180)
			(layer "F.SilkS")
			(hide yes)
			(effects
				(font
					(size 1.27 1.27)
				)
			)
		)
		(property "Value" ""
			(at 0 0 180)
			(layer "F.Fab")
			(effects
				(font
					(size 1.27 1.27)
				)
			)
		)
		(duplicate_pad_numbers_are_jumpers no)
		(fp_line
			(start 0.7874 0.4064)
			(end -0.7874 0.4064)
			(stroke
				(width 0.1524)
				(type default)
			)
			(layer "F.SilkS")
		)
		(fp_line
			(start 0.7874 -0.4064)
			(end 0.7874 0.4064)
			(stroke
				(width 0.1524)
				(type default)
			)
			(layer "F.SilkS")
		)
		(fp_line
			(start -0.7874 0.4064)
			(end -0.7874 -0.4064)
			(stroke
				(width 0.1524)
				(type default)
			)
			(layer "F.SilkS")
		)
		(fp_line
			(start -0.7874 -0.4064)
			(end 0.7874 -0.4064)
			(stroke
				(width 0.1524)
				(type default)
			)
			(layer "F.SilkS")
		)
		(fp_line
			(start 0.67945 0.3048)
			(end 0.120396 0.3048)
			(stroke
				(width 0.1)
				(type default)
			)
			(layer "F.Fab")
		)
		(fp_line
			(start 0.67945 -0.3048)
			(end 0.67945 0.3048)
			(stroke
				(width 0.1)
				(type default)
			)
			(layer "F.Fab")
		)
		(fp_line
			(start 0.12065 -0.2794)
			(end 0.12065 -0.3048)
			(stroke
				(width 0.1)
				(type default)
			)
			(layer "F.Fab")
		)
		(fp_line
			(start 0.12065 -0.3048)
			(end 0.67945 -0.3048)
			(stroke
				(width 0.1)
				(type default)
			)
			(layer "F.Fab")
		)
		(fp_line
			(start 0.120396 0.3048)
			(end 0.120396 0.2794)
			(stroke
				(width 0.1)
				(type default)
			)
			(layer "F.Fab")
		)
		(fp_line
			(start 0.120396 0.2794)
			(end -0.12065 0.2794)
			(stroke
				(width 0.1)
				(type default)
			)
			(layer "F.Fab")
		)
		(fp_line
			(start -0.12065 0.3048)
			(end -0.67945 0.3048)
			(stroke
				(width 0.1)
				(type default)
			)
			(layer "F.Fab")
		)
		(fp_line
			(start -0.12065 0.2794)
			(end -0.12065 0.3048)
			(stroke
				(width 0.1)
				(type default)
			)
			(layer "F.Fab")
		)
		(fp_line
			(start -0.12065 -0.2794)
			(end 0.12065 -0.2794)
			(stroke
				(width 0.1)
				(type default)
			)
			(layer "F.Fab")
		)
		(fp_line
			(start -0.12065 -0.305054)
			(end -0.12065 -0.2794)
			(stroke
				(width 0.1)
				(type default)
			)
			(layer "F.Fab")
		)
		(fp_line
			(start -0.67945 0.3048)
			(end -0.67945 -0.305054)
			(stroke
				(width 0.1)
				(type default)
			)
			(layer "F.Fab")
		)
		(fp_line
			(start -0.67945 -0.305054)
			(end -0.12065 -0.305054)
			(stroke
				(width 0.1)
				(type default)
			)
			(layer "F.Fab")
		)
		(pad "1" smd circle
			(at -0.40005 0 180)
			(size 0 0)
			(layers "F.Cu" "F.Mask" "F.Paste")
			(net "USB_CPU0_ADD_A1")
		)
		(pad "2" smd circle
			(at 0.40005 0 180)
			(size 0 0)
			(layers "F.Cu" "F.Mask" "F.Paste")
			(net "GND")
		)
	)
	(footprint ""
		(layer "F.Cu")
		(at 240.854484 -55.612792)
		(property "Reference" "C1991"
			(at 0 0 0)
			(layer "F.SilkS")
			(hide yes)
			(effects
				(font
					(size 1.27 1.27)
				)
			)
		)
		(property "Value" ""
			(at 0 0 0)
			(layer "F.Fab")
			(effects
				(font
					(size 1.27 1.27)
				)
			)
		)
		(duplicate_pad_numbers_are_jumpers no)
		(fp_line
			(start -0.299974 -0.150114)
			(end 0.299974 -0.150114)
			(stroke
				(width 0.1)
				(type default)
			)
			(layer "F.Fab")
		)
		(fp_line
			(start -0.299974 0.150114)
			(end -0.299974 -0.150114)
			(stroke
				(width 0.1)
				(type default)
			)
			(layer "F.Fab")
		)
		(fp_line
			(start 0.299974 -0.150114)
			(end 0.299974 0.150114)
			(stroke
				(width 0.1)
				(type default)
			)
			(layer "F.Fab")
		)
		(fp_line
			(start 0.299974 0.150114)
			(end -0.299974 0.150114)
			(stroke
				(width 0.1)
				(type default)
			)
			(layer "F.Fab")
		)
		(pad "1" smd rect
			(at -0.2667 0)
			(size 0.3048 0.381)
			(layers "F.Cu" "F.Mask" "F.Paste")
			(net "P3E_CPU0_P4_TX_C_DP<2>")
		)
		(pad "2" smd rect
			(at 0.2667 0)
			(size 0.3048 0.381)
			(layers "F.Cu" "F.Mask" "F.Paste")
			(net "P3E_CPU0_P4_TX_DP<2>")
		)
	)
	(footprint ""
		(layer "F.Cu")
		(at 75.49515 -381.48006 180)
		(property "Reference" "C740"
			(at 0 0 180)
			(layer "F.SilkS")
			(hide yes)
			(effects
				(font
					(size 1.27 1.27)
				)
			)
		)
		(property "Value" ""
			(at 0 0 180)
			(layer "F.Fab")
			(effects
				(font
					(size 1.27 1.27)
				)
			)
		)
		(duplicate_pad_numbers_are_jumpers no)
		(fp_line
			(start 0.299974 0.150114)
			(end -0.299974 0.150114)
			(stroke
				(width 0.1)
				(type default)
			)
			(layer "F.Fab")
		)
		(fp_line
			(start 0.299974 -0.150114)
			(end 0.299974 0.150114)
			(stroke
				(width 0.1)
				(type default)
			)
			(layer "F.Fab")
		)
		(fp_line
			(start -0.299974 0.150114)
			(end -0.299974 -0.150114)
			(stroke
				(width 0.1)
				(type default)
			)
			(layer "F.Fab")
		)
		(fp_line
			(start -0.299974 -0.150114)
			(end 0.299974 -0.150114)
			(stroke
				(width 0.1)
				(type default)
			)
			(layer "F.Fab")
		)
		(pad "1" smd rect
			(at -0.2667 0 180)
			(size 0.3048 0.381)
			(layers "F.Cu" "F.Mask" "F.Paste")
			(net "P5E_CPU1_P1_TX_C_DN<0>")
		)
		(pad "2" smd rect
			(at 0.2667 0 180)
			(size 0.3048 0.381)
			(layers "F.Cu" "F.Mask" "F.Paste")
			(net "P5E_CPU1_P1_TX_DN<0>")
		)
	)
	(footprint ""
		(layer "F.Cu")
		(at 393.762484 -392.48588 180)
		(property "Reference" "R1093"
			(at 0 0 180)
			(layer "F.SilkS")
			(hide yes)
			(effects
				(font
					(size 1.27 1.27)
				)
			)
		)
		(property "Value" ""
			(at 0 0 180)
			(layer "F.Fab")
			(effects
				(font
					(size 1.27 1.27)
				)
			)
		)
		(duplicate_pad_numbers_are_jumpers no)
		(fp_line
			(start 0.7874 0.4064)
			(end -0.7874 0.4064)
			(stroke
				(width 0.1524)
				(type default)
			)
			(layer "F.SilkS")
		)
		(fp_line
			(start 0.7874 -0.4064)
			(end 0.7874 0.4064)
			(stroke
				(width 0.1524)
				(type default)
			)
			(layer "F.SilkS")
		)
		(fp_line
			(start -0.7874 0.4064)
			(end -0.7874 -0.4064)
			(stroke
				(width 0.1524)
				(type default)
			)
			(layer "F.SilkS")
		)
		(fp_line
			(start -0.7874 -0.4064)
			(end 0.7874 -0.4064)
			(stroke
				(width 0.1524)
				(type default)
			)
			(layer "F.SilkS")
		)
		(fp_line
			(start 0.67945 0.3048)
			(end 0.120396 0.3048)
			(stroke
				(width 0.1)
				(type default)
			)
			(layer "F.Fab")
		)
		(fp_line
			(start 0.67945 -0.3048)
			(end 0.67945 0.3048)
			(stroke
				(width 0.1)
				(type default)
			)
			(layer "F.Fab")
		)
		(fp_line
			(start 0.12065 -0.2794)
			(end 0.12065 -0.3048)
			(stroke
				(width 0.1)
				(type default)
			)
			(layer "F.Fab")
		)
		(fp_line
			(start 0.12065 -0.3048)
			(end 0.67945 -0.3048)
			(stroke
				(width 0.1)
				(type default)
			)
			(layer "F.Fab")
		)
		(fp_line
			(start 0.120396 0.3048)
			(end 0.120396 0.2794)
			(stroke
				(width 0.1)
				(type default)
			)
			(layer "F.Fab")
		)
		(fp_line
			(start 0.120396 0.2794)
			(end -0.12065 0.2794)
			(stroke
				(width 0.1)
				(type default)
			)
			(layer "F.Fab")
		)
		(fp_line
			(start -0.12065 0.3048)
			(end -0.67945 0.3048)
			(stroke
				(width 0.1)
				(type default)
			)
			(layer "F.Fab")
		)
		(fp_line
			(start -0.12065 0.2794)
			(end -0.12065 0.3048)
			(stroke
				(width 0.1)
				(type default)
			)
			(layer "F.Fab")
		)
		(fp_line
			(start -0.12065 -0.2794)
			(end 0.12065 -0.2794)
			(stroke
				(width 0.1)
				(type default)
			)
			(layer "F.Fab")
		)
		(fp_line
			(start -0.12065 -0.305054)
			(end -0.12065 -0.2794)
			(stroke
				(width 0.1)
				(type default)
			)
			(layer "F.Fab")
		)
		(fp_line
			(start -0.67945 0.3048)
			(end -0.67945 -0.305054)
			(stroke
				(width 0.1)
				(type default)
			)
			(layer "F.Fab")
		)
		(fp_line
			(start -0.67945 -0.305054)
			(end -0.12065 -0.305054)
			(stroke
				(width 0.1)
				(type default)
			)
			(layer "F.Fab")
		)
		(pad "1" smd rect
			(at -0.40005 0)
			(size 0.4572 0.508)
			(layers "F.Cu" "F.Mask" "F.Paste")
			(net "P1V8_CPU0_RT_1D")
		)
		(pad "2" smd rect
			(at 0.40005 0)
			(size 0.4572 0.508)
			(layers "F.Cu" "F.Mask" "F.Paste")
			(net "P1V8_CPU0_RT3_1A_1D")
		)
	)
	(footprint ""
		(layer "F.Cu")
		(at 140.385546 -75.19924 -90)
		(property "Reference" "PR6003"
			(at 0 0 270)
			(layer "F.SilkS")
			(hide yes)
			(effects
				(font
					(size 1.27 1.27)
				)
			)
		)
		(property "Value" ""
			(at 0 0 270)
			(layer "F.Fab")
			(effects
				(font
					(size 1.27 1.27)
				)
			)
		)
		(duplicate_pad_numbers_are_jumpers no)
		(fp_line
			(start -0.7874 0.4064)
			(end -0.7874 -0.4064)
			(stroke
				(width 0.1524)
				(type default)
			)
			(layer "F.SilkS")
		)
		(fp_line
			(start 0.7874 0.4064)
			(end -0.7874 0.4064)
			(stroke
				(width 0.1524)
				(type default)
			)
			(layer "F.SilkS")
		)
		(fp_line
			(start -0.7874 -0.4064)
			(end 0.7874 -0.4064)
			(stroke
				(width 0.1524)
				(type default)
			)
			(layer "F.SilkS")
		)
		(fp_line
			(start 0.7874 -0.4064)
			(end 0.7874 0.4064)
			(stroke
				(width 0.1524)
				(type default)
			)
			(layer "F.SilkS")
		)
		(fp_line
			(start -0.67945 0.3048)
			(end -0.67945 -0.305054)
			(stroke
				(width 0.1)
				(type default)
			)
			(layer "F.Fab")
		)
		(fp_line
			(start -0.12065 0.3048)
			(end -0.67945 0.3048)
			(stroke
				(width 0.1)
				(type default)
			)
			(layer "F.Fab")
		)
		(fp_line
			(start 0.120396 0.3048)
			(end 0.120396 0.2794)
			(stroke
				(width 0.1)
				(type default)
			)
			(layer "F.Fab")
		)
		(fp_line
			(start 0.67945 0.3048)
			(end 0.120396 0.3048)
			(stroke
				(width 0.1)
				(type default)
			)
			(layer "F.Fab")
		)
		(fp_line
			(start -0.12065 0.2794)
			(end -0.12065 0.3048)
			(stroke
				(width 0.1)
				(type default)
			)
			(layer "F.Fab")
		)
		(fp_line
			(start 0.120396 0.2794)
			(end -0.12065 0.2794)
			(stroke
				(width 0.1)
				(type default)
			)
			(layer "F.Fab")
		)
		(fp_line
			(start -0.12065 -0.2794)
			(end 0.12065 -0.2794)
			(stroke
				(width 0.1)
				(type default)
			)
			(layer "F.Fab")
		)
		(fp_line
			(start 0.12065 -0.2794)
			(end 0.12065 -0.3048)
			(stroke
				(width 0.1)
				(type default)
			)
			(layer "F.Fab")
		)
		(fp_line
			(start 0.12065 -0.3048)
			(end 0.67945 -0.3048)
			(stroke
				(width 0.1)
				(type default)
			)
			(layer "F.Fab")
		)
		(fp_line
			(start 0.67945 -0.3048)
			(end 0.67945 0.3048)
			(stroke
				(width 0.1)
				(type default)
			)
			(layer "F.Fab")
		)
		(fp_line
			(start -0.67945 -0.305054)
			(end -0.12065 -0.305054)
			(stroke
				(width 0.1)
				(type default)
			)
			(layer "F.Fab")
		)
		(fp_line
			(start -0.12065 -0.305054)
			(end -0.12065 -0.2794)
			(stroke
				(width 0.1)
				(type default)
			)
			(layer "F.Fab")
		)
		(pad "1" smd circle
			(at -0.40005 0 270)
			(size 0 0)
			(layers "F.Cu" "F.Mask" "F.Paste")
			(net "P1V8_AUX_CS")
		)
		(pad "2" smd circle
			(at 0.40005 0 270)
			(size 0 0)
			(layers "F.Cu" "F.Mask" "F.Paste")
			(net "GND")
		)
	)
	(footprint ""
		(layer "F.Cu")
		(at 257.242056 -115.86337 180)
		(property "Reference" "R3720"
			(at 0 0 180)
			(layer "F.SilkS")
			(hide yes)
			(effects
				(font
					(size 1.27 1.27)
				)
			)
		)
		(property "Value" ""
			(at 0 0 180)
			(layer "F.Fab")
			(effects
				(font
					(size 1.27 1.27)
				)
			)
		)
		(duplicate_pad_numbers_are_jumpers no)
		(fp_line
			(start 0.7874 0.4064)
			(end -0.7874 0.4064)
			(stroke
				(width 0.1524)
				(type default)
			)
			(layer "F.SilkS")
		)
		(fp_line
			(start 0.7874 -0.4064)
			(end 0.7874 0.4064)
			(stroke
				(width 0.1524)
				(type default)
			)
			(layer "F.SilkS")
		)
		(fp_line
			(start -0.7874 0.4064)
			(end -0.7874 -0.4064)
			(stroke
				(width 0.1524)
				(type default)
			)
			(layer "F.SilkS")
		)
		(fp_line
			(start -0.7874 -0.4064)
			(end 0.7874 -0.4064)
			(stroke
				(width 0.1524)
				(type default)
			)
			(layer "F.SilkS")
		)
		(fp_line
			(start 0.67945 0.3048)
			(end 0.120396 0.3048)
			(stroke
				(width 0.1)
				(type default)
			)
			(layer "F.Fab")
		)
		(fp_line
			(start 0.67945 -0.3048)
			(end 0.67945 0.3048)
			(stroke
				(width 0.1)
				(type default)
			)
			(layer "F.Fab")
		)
		(fp_line
			(start 0.12065 -0.2794)
			(end 0.12065 -0.3048)
			(stroke
				(width 0.1)
				(type default)
			)
			(layer "F.Fab")
		)
		(fp_line
			(start 0.12065 -0.3048)
			(end 0.67945 -0.3048)
			(stroke
				(width 0.1)
				(type default)
			)
			(layer "F.Fab")
		)
		(fp_line
			(start 0.120396 0.3048)
			(end 0.120396 0.2794)
			(stroke
				(width 0.1)
				(type default)
			)
			(layer "F.Fab")
		)
		(fp_line
			(start 0.120396 0.2794)
			(end -0.12065 0.2794)
			(stroke
				(width 0.1)
				(type default)
			)
			(layer "F.Fab")
		)
		(fp_line
			(start -0.12065 0.3048)
			(end -0.67945 0.3048)
			(stroke
				(width 0.1)
				(type default)
			)
			(layer "F.Fab")
		)
		(fp_line
			(start -0.12065 0.2794)
			(end -0.12065 0.3048)
			(stroke
				(width 0.1)
				(type default)
			)
			(layer "F.Fab")
		)
		(fp_line
			(start -0.12065 -0.2794)
			(end 0.12065 -0.2794)
			(stroke
				(width 0.1)
				(type default)
			)
			(layer "F.Fab")
		)
		(fp_line
			(start -0.12065 -0.305054)
			(end -0.12065 -0.2794)
			(stroke
				(width 0.1)
				(type default)
			)
			(layer "F.Fab")
		)
		(fp_line
			(start -0.67945 0.3048)
			(end -0.67945 -0.305054)
			(stroke
				(width 0.1)
				(type default)
			)
			(layer "F.Fab")
		)
		(fp_line
			(start -0.67945 -0.305054)
			(end -0.12065 -0.305054)
			(stroke
				(width 0.1)
				(type default)
			)
			(layer "F.Fab")
		)
		(pad "1" smd circle
			(at -0.40005 0 180)
			(size 0 0)
			(layers "F.Cu" "F.Mask" "F.Paste")
			(net "SMB_LM75_2_3V3AUX_SDA_R")
		)
		(pad "2" smd circle
			(at 0.40005 0 180)
			(size 0 0)
			(layers "F.Cu" "F.Mask" "F.Paste")
			(net "SMB_LM75_2_3V3AUX_SDA")
		)
	)
)
